# T6G (Grand Teton) — schematic netlist excerpt (pin names and nets, part order shuffled) for the footprints in the layout excerpt that follows; sources: Cadence DE-HDL packaged netlist, KiCad conversion of 04192023_DAF0TMB3IC0_F0TG_MB_C_brd_V02_OCP.brd

PU6502  ISL69260IRAZT  ISL69260IRAZ-T IC  pkg QFN40_TH_0-4_5X5XE  page 362
  PWM0  = NC_P0V9_RETIMER_CPU0_PWM8
  PWM1  = NC_P0V9_RETIMER_CPU0_PWM7
  PWM2  = NC_P0V9_RETIMER_CPU0_PWM6
  PWM3  = NC_P0V9_RETIMER_CPU0_PWM5
  PWM4  = NC_P0V9_RETIMER_CPU0_PWM4
  PWM5  = NC_P0V9_RETIMER_CPU0_PWM3
  PWM6  = P0V9_RETIMER_CPU0_PWM2
  PWM7  = P0V9_RETIMER_CPU0_PWM1
  PMSDA  = P0V9_RETIMER_CPU0_PMSDA_R
  PMSCL  = P0V9_RETIMER_CPU0_PMSCL_R
  \npmalert#\  = TP_P0V9_RETIMER_CPU0_PMALERT
  PG0  = PWRGD_P0V9_RETIMER_CPU0_R
  EN0  = P0V9_RETIMER_CPU0_EN0_R
  \nvrhot#\  = P0V9_RETIMER_CPU0_VRHOT
  \npinalert#||npsyscrit#\  = P0V9_RETIMER_CPU0_INALERT
  PG1  = NC_P0V9_RETIMER_CPU0_PG1
  SVCLK  = P0V9_RETIMER_CPU0_SVID_CLK
  SVDATA  = P0V9_RETIMER_CPU0_SVID_SDA
  \nsvalert#\  = TP_P0V9_RETIMER_CPU0_SVID_ALERT_N
  EN1  = P0V9_RETIMER_CPU0_EN1_R
  VSEN0  = P0V9_RETIMER_CPU0_SENSE_R_P
  RGND0  = P0V9_RETIMER_CPU0_SENSE_SH_N
  CS7  = P0V9_RETIMER_CPU0_IMON1
  CS6  = P0V9_RETIMER_CPU0_IMON2
  CS5  = NC_P0V9_RETIMER_CPU0_IMON3
  CS4  = NC_P0V9_RETIMER_CPU0_IMON4
  CS3  = NC_P0V9_RETIMER_CPU0_IMON5
  CS2  = NC_P0V9_RETIMER_CPU0_IMON6
  CS1  = NC_P0V9_RETIMER_CPU0_IMON7
  CS0  = NC_P0V9_RETIMER_CPU0_IMON8
  RGND1  = GND
  VSEN1  = GND
  CFP  = P0V9_RETIMER_CPU0_CFP
  ADDR_CFG  = P0V9_RETIMER_CPU0_ADDR
  TEMP0  = P0V9_RETIMER_CPU0_TEMP0
  \temp1||isys\  = P0V9_RETIMER_CPU0_TEMP1_R
  \vmon||iinsen||vsys||isys\  = P0V9_RETIMER_CPU0_VMON
  \vinsen||vsys\  = P0V9_RETIMER_CPU0_VINSEN
  VCC  = P0V9_RETIMER_CPU0_VCC
  VCCS  = PV09_RETIMER_CPU0_VCCS
  TH_GND  = GND

(kicad_pcb
	(version 20260206)
	(generator "pcbnew")
	(generator_version "10.0")
	(general
		(thickness 1.6)
		(legacy_teardrops no)
	)
	(paper "A4")
	(title_block
		(title "04192023_DAF0TMB3IC0_F0TG_MB_C_brd_V02_OCP.brd")
		(comment 1 "Grand Teton / footprint 2361 of 8354 (PU6502), pads 1-41 of 41")
	)
	(layers
		(0 "F.Cu" signal "TOP")
		(4 "In1.Cu" signal "GND")
		(6 "In2.Cu" signal "IN1")
		(8 "In3.Cu" signal "GND1")
		(10 "In4.Cu" signal "IN2")
		(12 "In5.Cu" signal "GND2")
		(14 "In6.Cu" signal "IN3")
		(16 "In7.Cu" signal "GND3")
		(18 "In8.Cu" signal "VCC")
		(20 "In9.Cu" signal "VCC1")
		(22 "In10.Cu" signal "GND4")
		(24 "In11.Cu" signal "IN4")
		(26 "In12.Cu" signal "GND5")
		(28 "In13.Cu" signal "IN5")
		(30 "In14.Cu" signal "GND6")
		(32 "In15.Cu" signal "IN6")
		(34 "In16.Cu" signal "GND7")
		(2 "B.Cu" signal "BOTTOM")
		(9 "F.Adhes" user "F.Adhesive")
		(11 "B.Adhes" user "B.Adhesive")
		(13 "F.Paste" user "Package Geometry/Pastemask Top")
		(15 "B.Paste" user "Package Geometry/Pastemask Bottom")
		(5 "F.SilkS" user "Ref Des/Silkscreen Top")
		(7 "B.SilkS" user "Ref Des/Silkscreen Bottom")
		(1 "F.Mask" user "Board Geometry/Soldermask Top")
		(3 "B.Mask" user "Board Geometry/Soldermask Bottom")
		(17 "Dwgs.User" user "User.Drawings")
		(19 "Cmts.User" user "User.Comments")
		(21 "Eco1.User" user "User.Eco1")
		(23 "Eco2.User" user "User.Eco2")
		(25 "Edge.Cuts" user "Board Geometry/Outline")
		(27 "Margin" user)
		(31 "F.CrtYd" user "Package Geometry/Place Bound Top")
		(29 "B.CrtYd" user "Package Geometry/Place Bound Bottom")
		(35 "F.Fab" user "Ref Des/Assembly Top")
		(33 "B.Fab" user "Ref Des/Assembly Bottom")
	)
	(footprint ""
		(layer "F.Cu")
		(at 444.329566 -423.914824 -90)
		(property "Reference" "PU6502"
			(at -6.632956 -0.115824 0)
			(unlocked yes)
			(layer "F.SilkS")
			(effects
				(font
					(size 0.7874 0.5842)
					(thickness 0.1524)
				)
				(justify left)
			)
		)
		(property "Value" ""
			(at 0 0 270)
			(layer "F.Fab")
			(effects
				(font
					(size 1.27 1.27)
				)
			)
		)
		(duplicate_pad_numbers_are_jumpers no)
		(pad "1" smd rect
			(at -2.400046 -1.800098 180)
			(size 0.1778 0.6096)
			(layers "F.Cu" "F.Mask" "F.Paste")
			(net "NC_P0V9_RETIMER_CPU0_PWM8")
		)
		(pad "2" smd rect
			(at -2.400046 -1.400048 180)
			(size 0.1778 0.6096)
			(layers "F.Cu" "F.Mask" "F.Paste")
			(net "NC_P0V9_RETIMER_CPU0_PWM7")
		)
		(pad "3" smd rect
			(at -2.400046 -0.999998 180)
			(size 0.1778 0.6096)
			(layers "F.Cu" "F.Mask" "F.Paste")
			(net "NC_P0V9_RETIMER_CPU0_PWM6")
		)
		(pad "4" smd rect
			(at -2.400046 -0.599948 180)
			(size 0.1778 0.6096)
			(layers "F.Cu" "F.Mask" "F.Paste")
			(net "NC_P0V9_RETIMER_CPU0_PWM5")
		)
		(pad "5" smd rect
			(at -2.400046 -0.199898 180)
			(size 0.1778 0.6096)
			(layers "F.Cu" "F.Mask" "F.Paste")
			(net "NC_P0V9_RETIMER_CPU0_PWM4")
		)
		(pad "6" smd rect
			(at -2.400046 0.199898 180)
			(size 0.1778 0.6096)
			(layers "F.Cu" "F.Mask" "F.Paste")
			(net "NC_P0V9_RETIMER_CPU0_PWM3")
		)
		(pad "7" smd rect
			(at -2.400046 0.599948 180)
			(size 0.1778 0.6096)
			(layers "F.Cu" "F.Mask" "F.Paste")
			(net "P0V9_RETIMER_CPU0_PWM2")
		)
		(pad "8" smd rect
			(at -2.400046 0.999998 180)
			(size 0.1778 0.6096)
			(layers "F.Cu" "F.Mask" "F.Paste")
			(net "P0V9_RETIMER_CPU0_PWM1")
		)
		(pad "9" smd rect
			(at -2.400046 1.400048 180)
			(size 0.1778 0.6096)
			(layers "F.Cu" "F.Mask" "F.Paste")
			(net "P0V9_RETIMER_CPU0_PMSDA_R")
		)
		(pad "10" smd rect
			(at -2.400046 1.800098 180)
			(size 0.1778 0.6096)
			(layers "F.Cu" "F.Mask" "F.Paste")
			(net "P0V9_RETIMER_CPU0_PMSCL_R")
		)
		(pad "11" smd rect
			(at -1.800098 2.400046 270)
			(size 0.1778 0.6096)
			(layers "F.Cu" "F.Mask" "F.Paste")
			(net "TP_P0V9_RETIMER_CPU0_PMALERT")
		)
		(pad "12" smd rect
			(at -1.400048 2.400046 270)
			(size 0.1778 0.6096)
			(layers "F.Cu" "F.Mask" "F.Paste")
			(net "PWRGD_P0V9_RETIMER_CPU0_R")
		)
		(pad "13" smd rect
			(at -0.999998 2.400046 270)
			(size 0.1778 0.6096)
			(layers "F.Cu" "F.Mask" "F.Paste")
			(net "P0V9_RETIMER_CPU0_EN0_R")
		)
		(pad "14" smd rect
			(at -0.599948 2.400046 270)
			(size 0.1778 0.6096)
			(layers "F.Cu" "F.Mask" "F.Paste")
			(net "P0V9_RETIMER_CPU0_VRHOT")
		)
		(pad "15" smd rect
			(at -0.199898 2.400046 270)
			(size 0.1778 0.6096)
			(layers "F.Cu" "F.Mask" "F.Paste")
			(net "P0V9_RETIMER_CPU0_INALERT")
		)
		(pad "16" smd rect
			(at 0.199898 2.400046 270)
			(size 0.1778 0.6096)
			(layers "F.Cu" "F.Mask" "F.Paste")
			(net "NC_P0V9_RETIMER_CPU0_PG1")
		)
		(pad "17" smd rect
			(at 0.599948 2.400046 270)
			(size 0.1778 0.6096)
			(layers "F.Cu" "F.Mask" "F.Paste")
			(net "P0V9_RETIMER_CPU0_SVID_CLK")
		)
		(pad "18" smd rect
			(at 0.999998 2.400046 270)
			(size 0.1778 0.6096)
			(layers "F.Cu" "F.Mask" "F.Paste")
			(net "P0V9_RETIMER_CPU0_SVID_SDA")
		)
		(pad "19" smd rect
			(at 1.400048 2.400046 270)
			(size 0.1778 0.6096)
			(layers "F.Cu" "F.Mask" "F.Paste")
			(net "TP_P0V9_RETIMER_CPU0_SVID_ALERT_N")
		)
		(pad "20" smd rect
			(at 1.800098 2.400046 270)
			(size 0.1778 0.6096)
			(layers "F.Cu" "F.Mask" "F.Paste")
			(net "P0V9_RETIMER_CPU0_EN1_R")
		)
		(pad "21" smd rect
			(at 2.400046 1.800098 180)
			(size 0.1778 0.6096)
			(layers "F.Cu" "F.Mask" "F.Paste")
			(net "P0V9_RETIMER_CPU0_SENSE_R_P")
		)
		(pad "22" smd rect
			(at 2.400046 1.400048 180)
			(size 0.1778 0.6096)
			(layers "F.Cu" "F.Mask" "F.Paste")
			(net "P0V9_RETIMER_CPU0_SENSE_SH_N")
		)
		(pad "23" smd rect
			(at 2.400046 0.999998 180)
			(size 0.1778 0.6096)
			(layers "F.Cu" "F.Mask" "F.Paste")
			(net "P0V9_RETIMER_CPU0_IMON1")
		)
		(pad "24" smd rect
			(at 2.400046 0.599948 180)
			(size 0.1778 0.6096)
			(layers "F.Cu" "F.Mask" "F.Paste")
			(net "P0V9_RETIMER_CPU0_IMON2")
		)
		(pad "25" smd rect
			(at 2.400046 0.199898 180)
			(size 0.1778 0.6096)
			(layers "F.Cu" "F.Mask" "F.Paste")
			(net "NC_P0V9_RETIMER_CPU0_IMON3")
		)
		(pad "26" smd rect
			(at 2.400046 -0.199898 180)
			(size 0.1778 0.6096)
			(layers "F.Cu" "F.Mask" "F.Paste")
			(net "NC_P0V9_RETIMER_CPU0_IMON4")
		)
		(pad "27" smd rect
			(at 2.400046 -0.599948 180)
			(size 0.1778 0.6096)
			(layers "F.Cu" "F.Mask" "F.Paste")
			(net "NC_P0V9_RETIMER_CPU0_IMON5")
		)
		(pad "28" smd rect
			(at 2.400046 -0.999998 180)
			(size 0.1778 0.6096)
			(layers "F.Cu" "F.Mask" "F.Paste")
			(net "NC_P0V9_RETIMER_CPU0_IMON6")
		)
		(pad "29" smd rect
			(at 2.400046 -1.400048 180)
			(size 0.1778 0.6096)
			(layers "F.Cu" "F.Mask" "F.Paste")
			(net "NC_P0V9_RETIMER_CPU0_IMON7")
		)
		(pad "30" smd rect
			(at 2.400046 -1.800098 180)
			(size 0.1778 0.6096)
			(layers "F.Cu" "F.Mask" "F.Paste")
			(net "NC_P0V9_RETIMER_CPU0_IMON8")
		)
		(pad "31" smd rect
			(at 1.800098 -2.400046 270)
			(size 0.1778 0.6096)
			(layers "F.Cu" "F.Mask" "F.Paste")
			(net "GND")
		)
		(pad "32" smd rect
			(at 1.400048 -2.400046 270)
			(size 0.1778 0.6096)
			(layers "F.Cu" "F.Mask" "F.Paste")
			(net "GND")
		)
		(pad "33" smd rect
			(at 0.999998 -2.400046 270)
			(size 0.1778 0.6096)
			(layers "F.Cu" "F.Mask" "F.Paste")
			(net "P0V9_RETIMER_CPU0_CFP")
		)
		(pad "34" smd rect
			(at 0.599948 -2.400046 270)
			(size 0.1778 0.6096)
			(layers "F.Cu" "F.Mask" "F.Paste")
			(net "P0V9_RETIMER_CPU0_ADDR")
		)
		(pad "35" smd rect
			(at 0.199898 -2.400046 270)
			(size 0.1778 0.6096)
			(layers "F.Cu" "F.Mask" "F.Paste")
			(net "P0V9_RETIMER_CPU0_TEMP0")
		)
		(pad "36" smd rect
			(at -0.199898 -2.400046 270)
			(size 0.1778 0.6096)
			(layers "F.Cu" "F.Mask" "F.Paste")
			(net "P0V9_RETIMER_CPU0_TEMP1_R")
		)
		(pad "37" smd rect
			(at -0.599948 -2.400046 270)
			(size 0.1778 0.6096)
			(layers "F.Cu" "F.Mask" "F.Paste")
			(net "P0V9_RETIMER_CPU0_VMON")
		)
		(pad "38" smd rect
			(at -0.999998 -2.400046 270)
			(size 0.1778 0.6096)
			(layers "F.Cu" "F.Mask" "F.Paste")
			(net "P0V9_RETIMER_CPU0_VINSEN")
		)
		(pad "39" smd rect
			(at -1.400048 -2.400046 270)
			(size 0.1778 0.6096)
			(layers "F.Cu" "F.Mask" "F.Paste")
			(net "P0V9_RETIMER_CPU0_VCC")
		)
		(pad "40" smd rect
			(at -1.800098 -2.400046 270)
			(size 0.1778 0.6096)
			(layers "F.Cu" "F.Mask" "F.Paste")
			(net "PV09_RETIMER_CPU0_VCCS")
		)
		(pad "TH" smd rect
			(at 0 0 270)
			(size 3.6576 3.6576)
			(layers "F.Cu" "F.Mask" "F.Paste")
			(net "GND")
		)
	)
)
